(kicad_pcb
	(version 20260206)
	(generator "pcbnew")
	(generator_version "10.0")
	(general
		(thickness 1.6)
		(legacy_teardrops no)
	)
	(paper "A4")
	(title_block
		(title "pdpb — Lightning_PDPB_BRD.brd")
		(comment 1 "Lightning (Wiwynn / Facebook NVMe JBOF) / footprints 185-190 of 1140")
	)
	(layers
		(0 "F.Cu" signal "TOP")
		(4 "In1.Cu" signal "L2GND")
		(6 "In2.Cu" signal "L3")
		(8 "In3.Cu" signal "L4VCC")
		(10 "In4.Cu" signal "L5VCC")
		(12 "In5.Cu" signal "L6")
		(14 "In6.Cu" signal "L7GND")
		(2 "B.Cu" signal "BOTTOM")
		(9 "F.Adhes" user "F.Adhesive")
		(11 "B.Adhes" user "B.Adhesive")
		(13 "F.Paste" user "Package Geometry/Pastemask Top")
		(15 "B.Paste" user "Package Geometry/Pastemask Bottom")
		(5 "F.SilkS" user "Ref Des/Silkscreen Top")
		(7 "B.SilkS" user "Ref Des/Silkscreen Bottom")
		(1 "F.Mask" user "Board Geometry/Soldermask Top")
		(3 "B.Mask" user "Board Geometry/Soldermask Bottom")
		(17 "Dwgs.User" user "User.Drawings")
		(19 "Cmts.User" user "User.Comments")
		(21 "Eco1.User" user "User.Eco1")
		(23 "Eco2.User" user "User.Eco2")
		(25 "Edge.Cuts" user "Board Geometry/Outline")
		(27 "Margin" user)
		(31 "F.CrtYd" user "Package Geometry/Place Bound Top")
		(29 "B.CrtYd" user "Package Geometry/Place Bound Bottom")
		(35 "F.Fab" user "Ref Des/Assembly Top")
		(33 "B.Fab" user "Ref Des/Assembly Bottom")
	)
	(footprint ""
		(layer "F.Cu")
		(at 222.123 -451.104)
		(property "Reference" "Q30"
			(at 0 0 0)
			(layer "F.SilkS")
			(hide yes)
			(effects
				(font
					(size 1.27 1.27)
				)
			)
		)
		(property "Value" "2N7002A-7-GP"
			(at 0.127 -8.9662 0)
			(unlocked yes)
			(layer "F.Fab")
			(hide yes)
			(effects
				(font
					(size 1.016 1.016)
					(thickness 0.1524)
				)
			)
		)
		(property "Device Type" "SOT23DGS2D4H48"
			(at 0.127 -10.4902 0)
			(unlocked yes)
			(layer "F.Fab")
			(hide yes)
			(effects
				(font
					(size 1.016 1.016)
					(thickness 0.1524)
				)
			)
		)
		(duplicate_pad_numbers_are_jumpers no)
		(fp_line
			(start -1.651 -1.778)
			(end -1.651 1.778)
			(stroke
				(width 0.1524)
				(type default)
			)
			(layer "F.SilkS")
		)
		(fp_line
			(start -1.651 1.778)
			(end 1.651 1.778)
			(stroke
				(width 0.1524)
				(type default)
			)
			(layer "F.SilkS")
		)
		(fp_line
			(start 1.651 -1.778)
			(end -1.651 -1.778)
			(stroke
				(width 0.1524)
				(type default)
			)
			(layer "F.SilkS")
		)
		(fp_line
			(start 1.651 1.778)
			(end 1.651 -1.778)
			(stroke
				(width 0.1524)
				(type default)
			)
			(layer "F.SilkS")
		)
		(fp_poly
			(pts
				(xy -1.778 1.8796) (xy -1.778 -1.8796) (xy 1.778 -1.8796) (xy 1.778 1.8796)
			)
			(stroke
				(width 0)
				(type default)
			)
			(fill no)
			(layer "F.CrtYd")
		)
		(fp_poly
			(pts
				(xy -1.778 1.8796) (xy -1.778 -1.8796) (xy 1.778 -1.8796) (xy 1.778 1.8796)
			)
			(stroke
				(width 0)
				(type default)
			)
			(fill no)
			(layer "F.Fab")
		)
		(pad "D" smd custom
			(at 0 -0.9525)
			(size 0.1905 0.1905)
			(layers "F.Cu" "F.Mask" "F.Paste")
			(net "ATTN_LED_DR0_MOS_N")
			(options
				(clearance outline)
				(anchor circle)
			)
			(primitives
				(gr_poly
					(pts
						(arc
							(start -0.1778 0.5715)
							(mid -0.321484 0.511984)
							(end -0.381 0.3683)
						)
						(arc
							(start -0.381 -0.3683)
							(mid -0.321484 -0.511984)
							(end -0.1778 -0.5715)
						)
						(arc
							(start 0.1778 -0.5715)
							(mid 0.321484 -0.511984)
							(end 0.381 -0.3683)
						)
						(arc
							(start 0.381 0.3683)
							(mid 0.321484 0.511984)
							(end 0.1778 0.5715)
						)
					)
					(width 0)
					(fill yes)
				)
			)
		)
		(pad "G" smd custom
			(at -0.98425 0.9525)
			(size 0.1905 0.1905)
			(layers "F.Cu" "F.Mask" "F.Paste")
			(net "SSD0_CLK0_OE_MOS_N")
			(options
				(clearance outline)
				(anchor circle)
			)
			(primitives
				(gr_poly
					(pts
						(arc
							(start -0.1778 0.5715)
							(mid -0.321484 0.511984)
							(end -0.381 0.3683)
						)
						(arc
							(start -0.381 -0.3683)
							(mid -0.321484 -0.511984)
							(end -0.1778 -0.5715)
						)
						(arc
							(start 0.1778 -0.5715)
							(mid 0.321484 -0.511984)
							(end 0.381 -0.3683)
						)
						(arc
							(start 0.381 0.3683)
							(mid 0.321484 0.511984)
							(end 0.1778 0.5715)
						)
					)
					(width 0)
					(fill yes)
				)
			)
		)
		(pad "S" smd custom
			(at 0.98425 0.9525)
			(size 0.1905 0.1905)
			(layers "F.Cu" "F.Mask" "F.Paste")
			(net "ATTN_LED_DR0_R")
			(options
				(clearance outline)
				(anchor circle)
			)
			(primitives
				(gr_poly
					(pts
						(arc
							(start -0.1778 0.5715)
							(mid -0.321484 0.511984)
							(end -0.381 0.3683)
						)
						(arc
							(start -0.381 -0.3683)
							(mid -0.321484 -0.511984)
							(end -0.1778 -0.5715)
						)
						(arc
							(start 0.1778 -0.5715)
							(mid 0.321484 -0.511984)
							(end 0.381 -0.3683)
						)
						(arc
							(start 0.381 0.3683)
							(mid 0.321484 0.511984)
							(end 0.1778 0.5715)
						)
					)
					(width 0)
					(fill yes)
				)
			)
		)
	)
	(footprint ""
		(layer "F.Cu")
		(at 22.1488 -498.9068)
		(property "Reference" "R9812"
			(at 0 0 0)
			(layer "F.SilkS")
			(hide yes)
			(effects
				(font
					(size 1.27 1.27)
				)
			)
		)
		(property "Value" "2K2R5F-GP"
			(at 0 -8.9535 0)
			(unlocked yes)
			(layer "F.Fab")
			(hide yes)
			(effects
				(font
					(size 1.27 1.016)
					(thickness 0.1524)
				)
			)
		)
		(property "Device Type" "R805H24"
			(at 0 -10.6299 0)
			(unlocked yes)
			(layer "F.Fab")
			(hide yes)
			(effects
				(font
					(size 1.27 1.016)
					(thickness 0.1524)
				)
			)
		)
		(duplicate_pad_numbers_are_jumpers no)
		(fp_line
			(start -0.889 -1.7018)
			(end -0.889 0.2794)
			(stroke
				(width 0.1524)
				(type default)
			)
			(layer "F.SilkS")
		)
		(fp_line
			(start -0.889 0.0762)
			(end -0.889 1.7018)
			(stroke
				(width 0.1524)
				(type default)
			)
			(layer "F.SilkS")
		)
		(fp_line
			(start -0.889 1.7018)
			(end 0.889 1.7018)
			(stroke
				(width 0.1524)
				(type default)
			)
			(layer "F.SilkS")
		)
		(fp_line
			(start 0.889 -1.7018)
			(end -0.889 -1.7018)
			(stroke
				(width 0.1524)
				(type default)
			)
			(layer "F.SilkS")
		)
		(fp_line
			(start 0.889 -1.7018)
			(end 0.889 -0.381)
			(stroke
				(width 0.1524)
				(type default)
			)
			(layer "F.SilkS")
		)
		(fp_line
			(start 0.889 1.7018)
			(end 0.889 -0.508)
			(stroke
				(width 0.1524)
				(type default)
			)
			(layer "F.SilkS")
		)
		(fp_poly
			(pts
				(xy 0.9652 -1.778) (xy 0.9652 1.778) (xy -0.9652 1.778) (xy -0.9652 -1.778)
			)
			(stroke
				(width 0)
				(type default)
			)
			(fill no)
			(layer "F.CrtYd")
		)
		(fp_rect
			(start -0.9652 1.778)
			(end 0.9652 -1.778)
			(stroke
				(width 0)
				(type default)
			)
			(fill no)
			(layer "F.Fab")
		)
		(pad "1" smd rect
			(at 0 -0.9652)
			(size 1.397 1.143)
			(layers "F.Cu" "F.Mask" "F.Paste")
			(net "P12V_SSD5")
		)
		(pad "2" smd rect
			(at 0 0.9652)
			(size 1.397 1.143)
			(layers "F.Cu" "F.Mask" "F.Paste")
			(net "P12V_MOST5_GATE_D")
		)
	)
	(footprint ""
		(layer "F.Cu")
		(at 215.9 -300.9646 -90)
		(property "Reference" "Q37"
			(at 0 0 270)
			(layer "F.SilkS")
			(hide yes)
			(effects
				(font
					(size 1.27 1.27)
				)
			)
		)
		(property "Value" "2N7002A-7-GP"
			(at 0.127 -8.9662 270)
			(unlocked yes)
			(layer "F.Fab")
			(hide yes)
			(effects
				(font
					(size 1.016 1.016)
					(thickness 0.1524)
				)
			)
		)
		(property "Device Type" "SOT23DGS2D4H48"
			(at 0.127 -10.4902 270)
			(unlocked yes)
			(layer "F.Fab")
			(hide yes)
			(effects
				(font
					(size 1.016 1.016)
					(thickness 0.1524)
				)
			)
		)
		(duplicate_pad_numbers_are_jumpers no)
		(fp_line
			(start -1.651 1.778)
			(end 1.651 1.778)
			(stroke
				(width 0.1524)
				(type default)
			)
			(layer "F.SilkS")
		)
		(fp_line
			(start 1.651 1.778)
			(end 1.651 -1.778)
			(stroke
				(width 0.1524)
				(type default)
			)
			(layer "F.SilkS")
		)
		(fp_line
			(start -1.651 -1.778)
			(end -1.651 1.778)
			(stroke
				(width 0.1524)
				(type default)
			)
			(layer "F.SilkS")
		)
		(fp_line
			(start 1.651 -1.778)
			(end -1.651 -1.778)
			(stroke
				(width 0.1524)
				(type default)
			)
			(layer "F.SilkS")
		)
		(fp_poly
			(pts
				(xy -1.778 1.8796) (xy -1.778 -1.8796) (xy 1.778 -1.8796) (xy 1.778 1.8796)
			)
			(stroke
				(width 0)
				(type default)
			)
			(fill no)
			(layer "F.CrtYd")
		)
		(fp_poly
			(pts
				(xy -1.778 1.8796) (xy -1.778 -1.8796) (xy 1.778 -1.8796) (xy 1.778 1.8796)
			)
			(stroke
				(width 0)
				(type default)
			)
			(fill no)
			(layer "F.Fab")
		)
		(pad "D" smd custom
			(at 0 -0.9525 270)
			(size 0.1905 0.1905)
			(layers "F.Cu" "F.Mask" "F.Paste")
			(net "P12V_MOST2_GATE_D")
			(options
				(clearance outline)
				(anchor circle)
			)
			(primitives
				(gr_poly
					(pts
						(arc
							(start -0.1778 0.5715)
							(mid -0.321484 0.511984)
							(end -0.381 0.3683)
						)
						(arc
							(start -0.381 -0.3683)
							(mid -0.321484 -0.511984)
							(end -0.1778 -0.5715)
						)
						(arc
							(start 0.1778 -0.5715)
							(mid 0.321484 -0.511984)
							(end 0.381 -0.3683)
						)
						(arc
							(start 0.381 0.3683)
							(mid 0.321484 0.511984)
							(end 0.1778 0.5715)
						)
					)
					(width 0)
					(fill yes)
				)
			)
		)
		(pad "G" smd custom
			(at -0.98425 0.9525 270)
			(size 0.1905 0.1905)
			(layers "F.Cu" "F.Mask" "F.Paste")
			(net "P12V_MOST2_GATE")
			(options
				(clearance outline)
				(anchor circle)
			)
			(primitives
				(gr_poly
					(pts
						(arc
							(start -0.1778 0.5715)
							(mid -0.321484 0.511984)
							(end -0.381 0.3683)
						)
						(arc
							(start -0.381 -0.3683)
							(mid -0.321484 -0.511984)
							(end -0.1778 -0.5715)
						)
						(arc
							(start 0.1778 -0.5715)
							(mid 0.321484 -0.511984)
							(end 0.381 -0.3683)
						)
						(arc
							(start 0.381 0.3683)
							(mid 0.321484 0.511984)
							(end 0.1778 0.5715)
						)
					)
					(width 0)
					(fill yes)
				)
			)
		)
		(pad "S" smd custom
			(at 0.98425 0.9525 270)
			(size 0.1905 0.1905)
			(layers "F.Cu" "F.Mask" "F.Paste")
			(net "GND")
			(options
				(clearance outline)
				(anchor circle)
			)
			(primitives
				(gr_poly
					(pts
						(arc
							(start -0.1778 0.5715)
							(mid -0.321484 0.511984)
							(end -0.381 0.3683)
						)
						(arc
							(start -0.381 -0.3683)
							(mid -0.321484 -0.511984)
							(end -0.1778 -0.5715)
						)
						(arc
							(start 0.1778 -0.5715)
							(mid 0.321484 -0.511984)
							(end 0.381 -0.3683)
						)
						(arc
							(start 0.381 0.3683)
							(mid 0.321484 0.511984)
							(end 0.1778 0.5715)
						)
					)
					(width 0)
					(fill yes)
				)
			)
		)
	)
	(footprint ""
		(layer "F.Cu")
		(at 31.369 -197.9676 -90)
		(property "Reference" "Q67"
			(at 0 0 270)
			(layer "F.SilkS")
			(hide yes)
			(effects
				(font
					(size 1.27 1.27)
				)
			)
		)
		(property "Value" "2N7002A-7-GP"
			(at 0.127 -8.9662 270)
			(unlocked yes)
			(layer "F.Fab")
			(hide yes)
			(effects
				(font
					(size 1.016 1.016)
					(thickness 0.1524)
				)
			)
		)
		(property "Device Type" "SOT23DGS2D4H48"
			(at 0.127 -10.4902 270)
			(unlocked yes)
			(layer "F.Fab")
			(hide yes)
			(effects
				(font
					(size 1.016 1.016)
					(thickness 0.1524)
				)
			)
		)
		(duplicate_pad_numbers_are_jumpers no)
		(fp_line
			(start -1.651 1.778)
			(end 1.651 1.778)
			(stroke
				(width 0.1524)
				(type default)
			)
			(layer "F.SilkS")
		)
		(fp_line
			(start 1.651 1.778)
			(end 1.651 -1.778)
			(stroke
				(width 0.1524)
				(type default)
			)
			(layer "F.SilkS")
		)
		(fp_line
			(start -1.651 -1.778)
			(end -1.651 1.778)
			(stroke
				(width 0.1524)
				(type default)
			)
			(layer "F.SilkS")
		)
		(fp_line
			(start 1.651 -1.778)
			(end -1.651 -1.778)
			(stroke
				(width 0.1524)
				(type default)
			)
			(layer "F.SilkS")
		)
		(fp_poly
			(pts
				(xy -1.778 1.8796) (xy -1.778 -1.8796) (xy 1.778 -1.8796) (xy 1.778 1.8796)
			)
			(stroke
				(width 0)
				(type default)
			)
			(fill no)
			(layer "F.CrtYd")
		)
		(fp_poly
			(pts
				(xy -1.778 1.8796) (xy -1.778 -1.8796) (xy 1.778 -1.8796) (xy 1.778 1.8796)
			)
			(stroke
				(width 0)
				(type default)
			)
			(fill no)
			(layer "F.Fab")
		)
		(pad "D" smd custom
			(at 0 -0.9525 270)
			(size 0.1905 0.1905)
			(layers "F.Cu" "F.Mask" "F.Paste")
			(net "P12V_MOST8_GATE_D")
			(options
				(clearance outline)
				(anchor circle)
			)
			(primitives
				(gr_poly
					(pts
						(arc
							(start -0.1778 0.5715)
							(mid -0.321484 0.511984)
							(end -0.381 0.3683)
						)
						(arc
							(start -0.381 -0.3683)
							(mid -0.321484 -0.511984)
							(end -0.1778 -0.5715)
						)
						(arc
							(start 0.1778 -0.5715)
							(mid 0.321484 -0.511984)
							(end 0.381 -0.3683)
						)
						(arc
							(start 0.381 0.3683)
							(mid 0.321484 0.511984)
							(end 0.1778 0.5715)
						)
					)
					(width 0)
					(fill yes)
				)
			)
		)
		(pad "G" smd custom
			(at -0.98425 0.9525 270)
			(size 0.1905 0.1905)
			(layers "F.Cu" "F.Mask" "F.Paste")
			(net "P12V_MOST8_GATE")
			(options
				(clearance outline)
				(anchor circle)
			)
			(primitives
				(gr_poly
					(pts
						(arc
							(start -0.1778 0.5715)
							(mid -0.321484 0.511984)
							(end -0.381 0.3683)
						)
						(arc
							(start -0.381 -0.3683)
							(mid -0.321484 -0.511984)
							(end -0.1778 -0.5715)
						)
						(arc
							(start 0.1778 -0.5715)
							(mid 0.321484 -0.511984)
							(end 0.381 -0.3683)
						)
						(arc
							(start 0.381 0.3683)
							(mid 0.321484 0.511984)
							(end 0.1778 0.5715)
						)
					)
					(width 0)
					(fill yes)
				)
			)
		)
		(pad "S" smd custom
			(at 0.98425 0.9525 270)
			(size 0.1905 0.1905)
			(layers "F.Cu" "F.Mask" "F.Paste")
			(net "GND")
			(options
				(clearance outline)
				(anchor circle)
			)
			(primitives
				(gr_poly
					(pts
						(arc
							(start -0.1778 0.5715)
							(mid -0.321484 0.511984)
							(end -0.381 0.3683)
						)
						(arc
							(start -0.381 -0.3683)
							(mid -0.321484 -0.511984)
							(end -0.1778 -0.5715)
						)
						(arc
							(start 0.1778 -0.5715)
							(mid 0.321484 -0.511984)
							(end 0.381 -0.3683)
						)
						(arc
							(start 0.381 0.3683)
							(mid 0.321484 0.511984)
							(end 0.1778 0.5715)
						)
					)
					(width 0)
					(fill yes)
				)
			)
		)
	)
	(footprint ""
		(layer "F.Cu")
		(at 24.003 -260.473952 -90)
		(property "Reference" "SR1145"
			(at 0 0 270)
			(layer "F.SilkS")
			(hide yes)
			(effects
				(font
					(size 1.27 1.27)
				)
			)
		)
		(property "Value" "4K7R2F-GP"
			(at 0.064008 -3.993896 270)
			(unlocked yes)
			(layer "F.Fab")
			(hide yes)
			(effects
				(font
					(size 1.016 1.016)
					(thickness 0.1524)
				)
			)
		)
		(property "Device Type" "R402H16"
			(at 0.064008 -5.517896 270)
			(unlocked yes)
			(layer "F.Fab")
			(hide yes)
			(effects
				(font
					(size 1.016 1.016)
					(thickness 0.1524)
				)
			)
		)
		(duplicate_pad_numbers_are_jumpers no)
		(fp_line
			(start -0.508 -0.9398)
			(end -0.508 0.9398)
			(stroke
				(width 0.1524)
				(type default)
			)
			(layer "F.SilkS")
		)
		(fp_line
			(start 0.508 -0.9398)
			(end -0.508 -0.9398)
			(stroke
				(width 0.1524)
				(type default)
			)
			(layer "F.SilkS")
		)
		(fp_rect
			(start -0.508 0.9398)
			(end 0.508 -0.9398)
			(stroke
				(width 0)
				(type default)
			)
			(fill no)
			(layer "F.CrtYd")
		)
		(fp_rect
			(start -0.508 0.9398)
			(end 0.508 -0.9398)
			(stroke
				(width 0)
				(type default)
			)
			(fill no)
			(layer "F.Fab")
		)
		(pad "1" smd custom
			(at 0 -0.4445 270)
			(size 0.1397 0.1397)
			(layers "F.Cu" "F.Mask" "F.Paste")
			(net "P3V3")
			(options
				(clearance outline)
				(anchor circle)
			)
			(primitives
				(gr_poly
					(pts
						(arc
							(start -0.1778 -0.2794)
							(mid -0.249642 -0.249642)
							(end -0.2794 -0.1778)
						)
						(arc
							(start -0.2794 0.1778)
							(mid -0.249642 0.249642)
							(end -0.1778 0.2794)
						)
						(arc
							(start 0.1778 0.2794)
							(mid 0.249642 0.249642)
							(end 0.2794 0.1778)
						)
						(arc
							(start 0.2794 -0.1778)
							(mid 0.249642 -0.249642)
							(end 0.1778 -0.2794)
						)
					)
					(width 0)
					(fill yes)
				)
			)
		)
		(pad "2" smd custom
			(at 0 0.4445 270)
			(size 0.1397 0.1397)
			(layers "F.Cu" "F.Mask" "F.Paste")
			(net "SSD12_CLK0_OE_MOS_N")
			(options
				(clearance outline)
				(anchor circle)
			)
			(primitives
				(gr_poly
					(pts
						(arc
							(start -0.1778 -0.2794)
							(mid -0.249642 -0.249642)
							(end -0.2794 -0.1778)
						)
						(arc
							(start -0.2794 0.1778)
							(mid -0.249642 0.249642)
							(end -0.1778 0.2794)
						)
						(arc
							(start 0.1778 0.2794)
							(mid 0.249642 0.249642)
							(end 0.2794 0.1778)
						)
						(arc
							(start 0.2794 -0.1778)
							(mid 0.249642 -0.249642)
							(end 0.1778 -0.2794)
						)
					)
					(width 0)
					(fill yes)
				)
			)
		)
	)
	(footprint ""
		(layer "F.Cu")
		(at 15.5067 -498.7417 180)
		(property "Reference" "R9814"
			(at 0 0 180)
			(layer "F.SilkS")
			(hide yes)
			(effects
				(font
					(size 1.27 1.27)
				)
			)
		)
		(property "Value" "47KR2J-2-GP"
			(at 0.064008 -3.993896 180)
			(unlocked yes)
			(layer "F.Fab")
			(hide yes)
			(effects
				(font
					(size 1.016 1.016)
					(thickness 0.1524)
				)
			)
		)
		(property "Device Type" "R402H16"
			(at 0.064008 -5.517896 180)
			(unlocked yes)
			(layer "F.Fab")
			(hide yes)
			(effects
				(font
					(size 1.016 1.016)
					(thickness 0.1524)
				)
			)
		)
		(duplicate_pad_numbers_are_jumpers no)
		(fp_line
			(start 0.508 -0.9398)
			(end -0.508 -0.9398)
			(stroke
				(width 0.1524)
				(type default)
			)
			(layer "F.SilkS")
		)
		(fp_line
			(start -0.508 -0.9398)
			(end -0.508 0.9398)
			(stroke
				(width 0.1524)
				(type default)
			)
			(layer "F.SilkS")
		)
		(fp_rect
			(start -0.508 0.9398)
			(end 0.508 -0.9398)
			(stroke
				(width 0)
				(type default)
			)
			(fill no)
			(layer "F.CrtYd")
		)
		(fp_rect
			(start -0.508 0.9398)
			(end 0.508 -0.9398)
			(stroke
				(width 0)
				(type default)
			)
			(fill no)
			(layer "F.Fab")
		)
		(pad "1" smd custom
			(at 0 -0.4445 180)
			(size 0.1397 0.1397)
			(layers "F.Cu" "F.Mask" "F.Paste")
			(net "P12V")
			(options
				(clearance outline)
				(anchor circle)
			)
			(primitives
				(gr_poly
					(pts
						(arc
							(start -0.1778 -0.2794)
							(mid -0.249642 -0.249642)
							(end -0.2794 -0.1778)
						)
						(arc
							(start -0.2794 0.1778)
							(mid -0.249642 0.249642)
							(end -0.1778 0.2794)
						)
						(arc
							(start 0.1778 0.2794)
							(mid 0.249642 0.249642)
							(end 0.2794 0.1778)
						)
						(arc
							(start 0.2794 -0.1778)
							(mid 0.249642 -0.249642)
							(end 0.1778 -0.2794)
						)
					)
					(width 0)
					(fill yes)
				)
			)
		)
		(pad "2" smd custom
			(at 0 0.4445 180)
			(size 0.1397 0.1397)
			(layers "F.Cu" "F.Mask" "F.Paste")
			(net "P12V_MOST5_GATE")
			(options
				(clearance outline)
				(anchor circle)
			)
			(primitives
				(gr_poly
					(pts
						(arc
							(start -0.1778 -0.2794)
							(mid -0.249642 -0.249642)
							(end -0.2794 -0.1778)
						)
						(arc
							(start -0.2794 0.1778)
							(mid -0.249642 0.249642)
							(end -0.1778 0.2794)
						)
						(arc
							(start 0.1778 0.2794)
							(mid 0.249642 0.249642)
							(end 0.2794 0.1778)
						)
						(arc
							(start 0.2794 -0.1778)
							(mid 0.249642 -0.249642)
							(end 0.1778 -0.2794)
						)
					)
					(width 0)
					(fill yes)
				)
			)
		)
	)
)
